#ISCELL
  pure_quanta quanta_title_block_c *
  *
#ISCELL
  standard offpage *
  page124_i11
#CELL
  pure_quanta q_res *
  page124_i17
#CELL
  pure_quanta q_res *
  page124_i19
#ISCELL
  standard offpage *
  page124_i20
#CELL
  pure_quanta q_res *
  page124_i26
#ISCELL
  standard offpage *
  page124_i27
#CELL
  pure_quanta q_res *
  page124_i33
#ISCELL
  standard offpage *
  page124_i34
#ISCELL
  standard offpage *
  page124_i40
#CELL
  pure_quanta q_res *
  page124_i43
#ISCELL
  logical_power universal_power *
  page124_i51
#CELL
  pure_quanta q_res *
  page124_i52
#ISCELL
  standard offpage *
  page124_i54
#ISCELL
  standard offpage *
  page124_i57
#ISCELL
  standard offpage *
  page124_i58
#ISCELL
  logical_power universal_power *
  page124_i59
#CELL
  pure_quanta q_res *
  page124_i60
#CELL
  pure_quanta q_res *
  page124_i62
#CELL
  pure_quanta q_res *
  page124_i68
#ISCELL
  logical_power universal_power *
  page124_i69
#CELL
  pure_quanta q_res *
  page124_i70
#ISCELL
  logical_power universal_power *
  page124_i71
#CELL
  pure_quanta q_res *
  page124_i72
#ISCELL
  logical_power universal_power *
  page124_i73
#ISCELL
  logical_power universal_power *
  page124_i75
#CELL
  pure_quanta q_res *
  page124_i76
#CELL
  pure_quanta q_res *
  page124_i77
#CELL
  pure_quanta q_res *
  page124_i78
#CELL
  pure_quanta q_res *
  page124_i79
#ISCELL
  standard offpage *
  page124_i80
#CELL
  pure_quanta q_res *
  page124_i82
#ISCELL
  standard offpage *
  page124_i83
#CELL
  pure_quanta q_res *
  page124_i85
#ISCELL
  standard offpage *
  page124_i86
#CELL
  pure_quanta q_res *
  page124_i87
#ISCELL
  standard offpage *
  page124_i88
